# S9S_MB_2U (Grand Teton) — schematic netlist excerpt (pin names and nets, part order shuffled) for the footprints in the layout excerpt that follows; sources: Cadence DE-HDL packaged netlist, KiCad conversion of 03242023_DA0F0TMBIJ0_F0T_Motherboard_J_brd_V01_OCP.brd

C717  Q_CAP_DIFFBUS  DIFF BUS_0.22UF 6.3V 20% X6S  pkg C0201  page 176 : \1\ = P5E_CPU1_PE0_TX_C_DP<12> ; \2\ = P5E_CPU1_PE0_TX_DP<12>
R581  Q_RES  33.2 1% CHIP  pkg 0402LF  page 241 : A = SMB_SML0_3V3AUX_SCL ; B = SMB_SML0_3V3AUX_PCH_SCL
C437  Q_CAP  22UF 4V 20% X6S  pkg C0402  page 77 : A = PVCCFA_EHV_FIVRA_CPU1 ; B = GND

(kicad_pcb
	(version 20260206)
	(generator "pcbnew")
	(generator_version "10.0")
	(general
		(thickness 1.6)
		(legacy_teardrops no)
	)
	(paper "A4")
	(title_block
		(title "03242023_DA0F0TMBIJ0_F0T_Motherboard_J_brd_V01_OCP.brd")
		(comment 1 "Grand Teton / footprints 2928-2930 of 6105")
	)
	(layers
		(0 "F.Cu" signal "TOP")
		(4 "In1.Cu" signal "GND")
		(6 "In2.Cu" signal "IN1")
		(8 "In3.Cu" signal "GND1")
		(10 "In4.Cu" signal "IN2")
		(12 "In5.Cu" signal "GND2")
		(14 "In6.Cu" signal "IN3")
		(16 "In7.Cu" signal "GND3")
		(18 "In8.Cu" signal "VCC")
		(20 "In9.Cu" signal "VCC1")
		(22 "In10.Cu" signal "GND4")
		(24 "In11.Cu" signal "IN4")
		(26 "In12.Cu" signal "GND5")
		(28 "In13.Cu" signal "IN5")
		(30 "In14.Cu" signal "GND6")
		(32 "In15.Cu" signal "IN6")
		(34 "In16.Cu" signal "GND7")
		(2 "B.Cu" signal "BOTTOM")
		(9 "F.Adhes" user "F.Adhesive")
		(11 "B.Adhes" user "B.Adhesive")
		(13 "F.Paste" user "Package Geometry/Pastemask Top")
		(15 "B.Paste" user "Package Geometry/Pastemask Bottom")
		(5 "F.SilkS" user "Ref Des/Silkscreen Top")
		(7 "B.SilkS" user "Ref Des/Silkscreen Bottom")
		(1 "F.Mask" user "Board Geometry/Soldermask Top")
		(3 "B.Mask" user "Board Geometry/Soldermask Bottom")
		(17 "Dwgs.User" user "User.Drawings")
		(19 "Cmts.User" user "User.Comments")
		(21 "Eco1.User" user "User.Eco1")
		(23 "Eco2.User" user "User.Eco2")
		(25 "Edge.Cuts" user "Board Geometry/Outline")
		(27 "Margin" user)
		(31 "F.CrtYd" user "Package Geometry/Place Bound Top")
		(29 "B.CrtYd" user "Package Geometry/Place Bound Bottom")
		(35 "F.Fab" user "Ref Des/Assembly Top")
		(33 "B.Fab" user "Ref Des/Assembly Bottom")
	)
	(footprint ""
		(layer "F.Cu")
		(at 7.42188 -61.051948 180)
		(property "Reference" "R581"
			(at 0 0 180)
			(layer "F.SilkS")
			(hide yes)
			(effects
				(font
					(size 1.27 1.27)
				)
			)
		)
		(property "Value" ""
			(at 0 0 180)
			(layer "F.Fab")
			(effects
				(font
					(size 1.27 1.27)
				)
			)
		)
		(duplicate_pad_numbers_are_jumpers no)
		(fp_line
			(start 0.7874 0.4064)
			(end -0.7874 0.4064)
			(stroke
				(width 0.1524)
				(type default)
			)
			(layer "F.SilkS")
		)
		(fp_line
			(start 0.7874 -0.4064)
			(end 0.7874 0.4064)
			(stroke
				(width 0.1524)
				(type default)
			)
			(layer "F.SilkS")
		)
		(fp_line
			(start -0.7874 0.4064)
			(end -0.7874 -0.4064)
			(stroke
				(width 0.1524)
				(type default)
			)
			(layer "F.SilkS")
		)
		(fp_line
			(start -0.7874 -0.4064)
			(end 0.7874 -0.4064)
			(stroke
				(width 0.1524)
				(type default)
			)
			(layer "F.SilkS")
		)
		(fp_line
			(start 0.67945 0.3048)
			(end 0.120396 0.3048)
			(stroke
				(width 0.1)
				(type default)
			)
			(layer "F.Fab")
		)
		(fp_line
			(start 0.67945 -0.3048)
			(end 0.67945 0.3048)
			(stroke
				(width 0.1)
				(type default)
			)
			(layer "F.Fab")
		)
		(fp_line
			(start 0.12065 -0.2794)
			(end 0.12065 -0.3048)
			(stroke
				(width 0.1)
				(type default)
			)
			(layer "F.Fab")
		)
		(fp_line
			(start 0.12065 -0.3048)
			(end 0.67945 -0.3048)
			(stroke
				(width 0.1)
				(type default)
			)
			(layer "F.Fab")
		)
		(fp_line
			(start 0.120396 0.3048)
			(end 0.120396 0.2794)
			(stroke
				(width 0.1)
				(type default)
			)
			(layer "F.Fab")
		)
		(fp_line
			(start 0.120396 0.2794)
			(end -0.12065 0.2794)
			(stroke
				(width 0.1)
				(type default)
			)
			(layer "F.Fab")
		)
		(fp_line
			(start -0.12065 0.3048)
			(end -0.67945 0.3048)
			(stroke
				(width 0.1)
				(type default)
			)
			(layer "F.Fab")
		)
		(fp_line
			(start -0.12065 0.2794)
			(end -0.12065 0.3048)
			(stroke
				(width 0.1)
				(type default)
			)
			(layer "F.Fab")
		)
		(fp_line
			(start -0.12065 -0.2794)
			(end 0.12065 -0.2794)
			(stroke
				(width 0.1)
				(type default)
			)
			(layer "F.Fab")
		)
		(fp_line
			(start -0.12065 -0.305054)
			(end -0.12065 -0.2794)
			(stroke
				(width 0.1)
				(type default)
			)
			(layer "F.Fab")
		)
		(fp_line
			(start -0.67945 0.3048)
			(end -0.67945 -0.305054)
			(stroke
				(width 0.1)
				(type default)
			)
			(layer "F.Fab")
		)
		(fp_line
			(start -0.67945 -0.305054)
			(end -0.12065 -0.305054)
			(stroke
				(width 0.1)
				(type default)
			)
			(layer "F.Fab")
		)
		(pad "1" smd circle
			(at -0.40005 0 180)
			(size 0 0)
			(layers "F.Cu" "F.Mask" "F.Paste")
			(net "SMB_SML0_3V3AUX_SCL")
		)
		(pad "2" smd circle
			(at 0.40005 0 180)
			(size 0 0)
			(layers "F.Cu" "F.Mask" "F.Paste")
			(net "SMB_SML0_3V3AUX_PCH_SCL")
		)
	)
	(footprint ""
		(layer "F.Cu")
		(at 58.058558 -402.371052 -90)
		(property "Reference" "C717"
			(at 0 0 270)
			(layer "F.SilkS")
			(hide yes)
			(effects
				(font
					(size 1.27 1.27)
				)
			)
		)
		(property "Value" ""
			(at 0 0 270)
			(layer "F.Fab")
			(effects
				(font
					(size 1.27 1.27)
				)
			)
		)
		(duplicate_pad_numbers_are_jumpers no)
		(fp_line
			(start -0.299974 0.150114)
			(end -0.299974 -0.150114)
			(stroke
				(width 0.1)
				(type default)
			)
			(layer "F.Fab")
		)
		(fp_line
			(start 0.299974 0.150114)
			(end -0.299974 0.150114)
			(stroke
				(width 0.1)
				(type default)
			)
			(layer "F.Fab")
		)
		(fp_line
			(start -0.299974 -0.150114)
			(end 0.299974 -0.150114)
			(stroke
				(width 0.1)
				(type default)
			)
			(layer "F.Fab")
		)
		(fp_line
			(start 0.299974 -0.150114)
			(end 0.299974 0.150114)
			(stroke
				(width 0.1)
				(type default)
			)
			(layer "F.Fab")
		)
		(pad "1" smd rect
			(at -0.2667 0 270)
			(size 0.3048 0.381)
			(layers "F.Cu" "F.Mask" "F.Paste")
			(net "P5E_CPU1_PE0_TX_C_DP<12>")
		)
		(pad "2" smd rect
			(at 0.2667 0 270)
			(size 0.3048 0.381)
			(layers "F.Cu" "F.Mask" "F.Paste")
			(net "P5E_CPU1_PE0_TX_DP<12>")
		)
	)
	(footprint ""
		(layer "F.Cu")
		(at 105.306114 -260.36524 -90)
		(property "Reference" "C437"
			(at 0 0 270)
			(layer "F.SilkS")
			(hide yes)
			(effects
				(font
					(size 1.27 1.27)
				)
			)
		)
		(property "Value" ""
			(at 0 0 270)
			(layer "F.Fab")
			(effects
				(font
					(size 1.27 1.27)
				)
			)
		)
		(duplicate_pad_numbers_are_jumpers no)
		(fp_line
			(start -0.7874 0.4064)
			(end -0.7874 -0.4064)
			(stroke
				(width 0.1524)
				(type default)
			)
			(layer "F.SilkS")
		)
		(fp_line
			(start 0.7874 0.4064)
			(end -0.7874 0.4064)
			(stroke
				(width 0.1524)
				(type default)
			)
			(layer "F.SilkS")
		)
		(fp_line
			(start -0.7874 -0.4064)
			(end 0.7874 -0.4064)
			(stroke
				(width 0.1524)
				(type default)
			)
			(layer "F.SilkS")
		)
		(fp_line
			(start 0.7874 -0.4064)
			(end 0.7874 0.4064)
			(stroke
				(width 0.1524)
				(type default)
			)
			(layer "F.SilkS")
		)
		(fp_line
			(start -0.67945 0.3048)
			(end -0.67945 -0.305054)
			(stroke
				(width 0.1)
				(type default)
			)
			(layer "F.Fab")
		)
		(fp_line
			(start -0.12065 0.3048)
			(end -0.67945 0.3048)
			(stroke
				(width 0.1)
				(type default)
			)
			(layer "F.Fab")
		)
		(fp_line
			(start 0.120396 0.3048)
			(end 0.120396 0.2794)
			(stroke
				(width 0.1)
				(type default)
			)
			(layer "F.Fab")
		)
		(fp_line
			(start 0.67945 0.3048)
			(end 0.120396 0.3048)
			(stroke
				(width 0.1)
				(type default)
			)
			(layer "F.Fab")
		)
		(fp_line
			(start -0.12065 0.2794)
			(end -0.12065 0.3048)
			(stroke
				(width 0.1)
				(type default)
			)
			(layer "F.Fab")
		)
		(fp_line
			(start 0.120396 0.2794)
			(end -0.12065 0.2794)
			(stroke
				(width 0.1)
				(type default)
			)
			(layer "F.Fab")
		)
		(fp_line
			(start -0.12065 -0.2794)
			(end 0.12065 -0.2794)
			(stroke
				(width 0.1)
				(type default)
			)
			(layer "F.Fab")
		)
		(fp_line
			(start 0.12065 -0.2794)
			(end 0.12065 -0.3048)
			(stroke
				(width 0.1)
				(type default)
			)
			(layer "F.Fab")
		)
		(fp_line
			(start 0.12065 -0.3048)
			(end 0.67945 -0.3048)
			(stroke
				(width 0.1)
				(type default)
			)
			(layer "F.Fab")
		)
		(fp_line
			(start 0.67945 -0.3048)
			(end 0.67945 0.3048)
			(stroke
				(width 0.1)
				(type default)
			)
			(layer "F.Fab")
		)
		(fp_line
			(start -0.67945 -0.305054)
			(end -0.12065 -0.305054)
			(stroke
				(width 0.1)
				(type default)
			)
			(layer "F.Fab")
		)
		(fp_line
			(start -0.12065 -0.305054)
			(end -0.12065 -0.2794)
			(stroke
				(width 0.1)
				(type default)
			)
			(layer "F.Fab")
		)
		(pad "1" smd circle
			(at -0.40005 0 270)
			(size 0 0)
			(layers "F.Cu" "F.Mask" "F.Paste")
			(net "PVCCFA_EHV_FIVRA_CPU1")
		)
		(pad "2" smd circle
			(at 0.40005 0 270)
			(size 0 0)
			(layers "F.Cu" "F.Mask" "F.Paste")
			(net "GND")
		)
	)
)
